(kicad_pcb
	(version 20260206)
	(generator "pcbnew")
	(generator_version "10.0")
	(general
		(thickness 1.6)
		(legacy_teardrops no)
	)
	(paper "A4")
	(title_block
		(title "04192023_DAF0TMB3IC0_F0TG_MB_C_brd_V02_OCP.brd")
		(comment 1 "Grand Teton / footprint 655 of 8354 (U6013), pads 337-354 of 354")
	)
	(layers
		(0 "F.Cu" signal "TOP")
		(4 "In1.Cu" signal "GND")
		(6 "In2.Cu" signal "IN1")
		(8 "In3.Cu" signal "GND1")
		(10 "In4.Cu" signal "IN2")
		(12 "In5.Cu" signal "GND2")
		(14 "In6.Cu" signal "IN3")
		(16 "In7.Cu" signal "GND3")
		(18 "In8.Cu" signal "VCC")
		(20 "In9.Cu" signal "VCC1")
		(22 "In10.Cu" signal "GND4")
		(24 "In11.Cu" signal "IN4")
		(26 "In12.Cu" signal "GND5")
		(28 "In13.Cu" signal "IN5")
		(30 "In14.Cu" signal "GND6")
		(32 "In15.Cu" signal "IN6")
		(34 "In16.Cu" signal "GND7")
		(2 "B.Cu" signal "BOTTOM")
		(9 "F.Adhes" user "F.Adhesive")
		(11 "B.Adhes" user "B.Adhesive")
		(13 "F.Paste" user "Package Geometry/Pastemask Top")
		(15 "B.Paste" user "Package Geometry/Pastemask Bottom")
		(5 "F.SilkS" user "Ref Des/Silkscreen Top")
		(7 "B.SilkS" user "Ref Des/Silkscreen Bottom")
		(1 "F.Mask" user "Board Geometry/Soldermask Top")
		(3 "B.Mask" user "Board Geometry/Soldermask Bottom")
		(17 "Dwgs.User" user "User.Drawings")
		(19 "Cmts.User" user "User.Comments")
		(21 "Eco1.User" user "User.Eco1")
		(23 "Eco2.User" user "User.Eco2")
		(25 "Edge.Cuts" user "Board Geometry/Outline")
		(27 "Margin" user)
		(31 "F.CrtYd" user "Package Geometry/Place Bound Top")
		(29 "B.CrtYd" user "Package Geometry/Place Bound Bottom")
		(35 "F.Fab" user "Ref Des/Assembly Top")
		(33 "B.Fab" user "Ref Des/Assembly Bottom")
	)
	(footprint ""
		(layer "F.Cu")
		(at 379.567948 -395.724634)
		(property "Reference" "U6013"
			(at -8.471916 -7.649972 0)
			(unlocked yes)
			(layer "F.SilkS")
			(effects
				(font
					(size 0.7874 0.5842)
					(thickness 0.1524)
				)
				(justify left)
			)
		)
		(property "Value" ""
			(at 0 0 0)
			(layer "F.Fab")
			(effects
				(font
					(size 1.27 1.27)
				)
			)
		)
		(duplicate_pad_numbers_are_jumpers no)
		(pad "P10" smd circle
			(at 8.802624 -1.431798)
			(size 0.381 0.381)
			(layers "F.Cu" "F.Mask" "F.Paste")
			(net "P5E_CPU0_P3_TX_BUF_DN<15>")
		)
		(pad "P29" smd circle
			(at 8.802624 2.032254)
			(size 0.381 0.381)
			(layers "F.Cu" "F.Mask" "F.Paste")
			(net "P5E_CPU0_P3_RX_DN<15>")
		)
		(pad "R1" smd oval
			(at 8.64997 -3.938524)
			(size 0.254 0.3302)
			(layers "F.Cu" "F.Mask" "F.Paste")
			(net "P5E_CPU0_P3_RX_BUF_DP<15>")
		)
		(pad "R35" smd oval
			(at 8.64997 3.940048)
			(size 0.254 0.3302)
			(layers "F.Cu" "F.Mask" "F.Paste")
			(net "P5E_CPU0_P3_TX_C_DP<15>")
		)
		(pad "T4" smd circle
			(at 8.402574 -2.817368)
			(size 0.381 0.381)
			(layers "F.Cu" "F.Mask" "F.Paste")
			(net "GND")
		)
		(pad "T13" smd circle
			(at 8.402574 -0.79629)
			(size 0.3048 0.3048)
			(layers "F.Cu" "F.Mask" "F.Paste")
			(net "GND")
		)
		(pad "T17" smd circle
			(at 8.402574 -0.296164)
			(size 0.3048 0.3048)
			(layers "F.Cu" "F.Mask" "F.Paste")
			(net "P0V9_CPU0_RT3_2A")
		)
		(pad "T20" smd circle
			(at 8.402574 0.203708)
			(size 0.3048 0.3048)
			(layers "F.Cu" "F.Mask" "F.Paste")
			(net "P0V9_CPU0_RT3_2A")
		)
		(pad "T22" smd circle
			(at 8.402574 0.703834)
			(size 0.3048 0.3048)
			(layers "F.Cu" "F.Mask" "F.Paste")
			(net "GND")
		)
		(pad "T32" smd circle
			(at 8.402574 2.724912)
			(size 0.381 0.381)
			(layers "F.Cu" "F.Mask" "F.Paste")
			(net "GND")
		)
		(pad "U2" smd circle
			(at 8.349996 -3.41884)
			(size 0.3048 0.3048)
			(layers "F.Cu" "F.Mask" "F.Paste")
			(net "GND")
		)
		(pad "U34" smd circle
			(at 8.349996 3.420364)
			(size 0.3048 0.3048)
			(layers "F.Cu" "F.Mask" "F.Paste")
			(net "GND")
		)
		(pad "V1" smd oval
			(at 8.050022 -3.938524)
			(size 0.254 0.3302)
			(layers "F.Cu" "F.Mask" "F.Paste")
			(net "GND")
		)
		(pad "V35" smd oval
			(at 8.050022 3.940048)
			(size 0.254 0.3302)
			(layers "F.Cu" "F.Mask" "F.Paste")
			(net "GND")
		)
		(pad "W7" smd circle
			(at 8.002524 -2.12471)
			(size 0.381 0.381)
			(layers "F.Cu" "F.Mask" "F.Paste")
			(net "P5E_CPU0_P3_TX_BUF_DP<14>")
		)
		(pad "W26" smd circle
			(at 8.002524 1.339342)
			(size 0.381 0.381)
			(layers "F.Cu" "F.Mask" "F.Paste")
			(net "P5E_CPU0_P3_RX_DP<14>")
		)
		(pad "Y2" smd circle
			(at 7.750048 -3.41884)
			(size 0.3048 0.3048)
			(layers "F.Cu" "F.Mask" "F.Paste")
			(net "P5E_CPU0_P3_RX_BUF_DN<14>")
		)
		(pad "Y34" smd circle
			(at 7.750048 3.420364)
			(size 0.3048 0.3048)
			(layers "F.Cu" "F.Mask" "F.Paste")
			(net "P5E_CPU0_P3_TX_C_DP<14>")
		)
	)
)
